FILE_TYPE = CONNECTIVITY;
{Allegro Design Entry HDL 16.6-p007 (v16-6-112F) 10/10/2012}
"PAGE_NUMBER" = 103;
0"NC";
1"GND\g";
2"GND\g";
3"GND\g";
4"GND\g";
5"GND\g";
6"GND\g";
7"GND\g";
8"GND\g";
9"GND\g";
10"GND\g";
11"GND\g";
12"GND\g";
13"GND\g";
14"GND\g";
15"GND\g";
16"GND\g";
17"GND\g";
18"GND\g";
19"GND\g";
20"GND\g";
21"GND\g";
22"GND\g";
23"GND\g";
24"GND\g";
25"CLK_100M_CPU0_RC_REFCLK0_DP";
26"CLK_100M_CPU0_RC_REFCLK1_DN";
27"CLK_100M_CPU0_RC_REFCLK1_DP";
28"CLK_100M_CPU0_BCLK1_DP";
29"CLK_100M_CPU0_BCLK2_DN";
30"CLK_100M_CPU0_BCLK2_DP";
31"CLK_100M_CPU0_PE_REFCLK_DN";
32"CLK_100M_CPU0_PE_REFCLK_DP";
33"CLK_100M_CPU0_RC_REFCLK0_DN";
34"CLK_100M_CPU0_BCLK0_DN";
35"CLK_100M_CPU0_BCLK0_DP";
36"CLK_100M_CPU0_BCLK1_DN";
37"CLK_100M_CPU0_PE_REFCLK_R_DN";
38"CLK_100M_CPU0_BCLK2_R_DP";
39"CLK_100M_CPU0_BCLK2_R_DN";
40"CLK_100M_CPU0_BCLK1_R_DP";
41"CLK_100M_CPU0_BCLK1_R_DN";
42"CLK_100M_CPU0_BCLK0_R_DN";
43"CLK_100M_CPU0_BCLK0_R_DP";
44"CLK_100M_CPU0_RC_REFCLK1_R_DP";
45"CLK_100M_CPU0_RC_REFCLK1_R_DN";
46"CLK_100M_CPU0_RC_REFCLK0_R_DP";
47"CLK_100M_CPU0_RC_REFCLK0_R_DN";
48"CLK_100M_CPU0_PE_REFCLK_R_DP";
49"CLK_100M_CPU1_RC_REFCLK0_DP";
50"CLK_100M_CPU1_RC_REFCLK1_DN";
51"CLK_100M_CPU1_RC_REFCLK1_DP";
52"CLK_100M_CPU1_BCLK1_DP";
53"CLK_100M_CPU1_BCLK2_DN";
54"CLK_100M_CPU1_BCLK2_DP";
55"CLK_100M_CPU1_PE_REFCLK_DN";
56"CLK_100M_CPU1_PE_REFCLK_DP";
57"CLK_100M_CPU1_RC_REFCLK0_DN";
58"CLK_100M_CPU1_BCLK0_DN";
59"CLK_100M_CPU1_BCLK0_DP";
60"CLK_100M_CPU1_BCLK1_DN";
61"CLK_100M_CPU1_RC_REFCLK1_R_DP";
62"CLK_100M_CPU1_RC_REFCLK1_R_DN";
63"CLK_100M_CPU1_RC_REFCLK0_R_DP";
64"CLK_100M_CPU1_RC_REFCLK0_R_DN";
65"CLK_100M_CPU1_PE_REFCLK_R_DP";
66"CLK_100M_CPU1_PE_REFCLK_R_DN";
67"CLK_100M_CPU1_BCLK2_R_DP";
68"CLK_100M_CPU1_BCLK2_R_DN";
69"CLK_100M_CPU1_BCLK1_R_DP";
70"CLK_100M_CPU1_BCLK1_R_DN";
71"CLK_100M_CPU1_BCLK0_R_DP";
72"CLK_100M_CPU1_BCLK0_R_DN";
%"RES"
"1","(300,1250)","0","mstr_discrete","I1";
;
CDS_SEC"1"
BOM_COST"SYS_CLOCK"
CDS_LIB"mstr_discrete"
SEC_TYPE"0402"
SEC"1"
CDS_LOCATION"R4D25"
ROOM"DB1200Z"
PART_NUMBER"G21796-182"
MATERIAL"CHIP"
PACK_TYPE"0402"
TOLERANCE"1%"
LOCATION"R4D25"
WATTAGE"1/16W"
VALUE"27.4";
"B"
$PN"2"34;
"A"
$PN"1"42;
%"RES"
"1","(300,2875)","0","mstr_discrete","I104";
;
CDS_SEC"1"
SEC"1"
SEC_TYPE"0402"
BOM_COST"SYS_CLOCK"
CDS_LIB"mstr_discrete"
CDS_LOCATION"R4D17"
ROOM"DB1200Z"
PART_NUMBER"G21796-182"
MATERIAL"CHIP"
PACK_TYPE"0402"
TOLERANCE"1%"
LOCATION"R4D17"
WATTAGE"1/16W"
VALUE"27.4";
"B"
$PN"2"30;
"A"
$PN"1"38;
%"RES"
"1","(300,2550)","0","mstr_discrete","I109";
;
CDS_SEC"1"
CDS_LOCATION"R4D14"
SEC"1"
BOM_COST"SYS_CLOCK"
ROOM"DB1200Z"
SEC_TYPE"0402"
CDS_LIB"mstr_discrete"
PART_NUMBER"G21796-182"
LOCATION"R4D14"
TOLERANCE"1%"
PACK_TYPE"0402"
MATERIAL"CHIP"
WATTAGE"1/16W"
VALUE"27.4";
"B"
$PN"2"29;
"A"
$PN"1"39;
%"RES"
"1","(300,2225)","0","mstr_discrete","I114";
;
CDS_SEC"1"
CDS_LIB"mstr_discrete"
ROOM"DB1200Z"
SEC"1"
BOM_COST"SYS_CLOCK"
SEC_TYPE"0402"
CDS_LOCATION"R4D22"
PART_NUMBER"G21796-182"
TOLERANCE"1%"
PACK_TYPE"0402"
MATERIAL"CHIP"
LOCATION"R4D22"
WATTAGE"1/16W"
VALUE"27.4";
"B"
$PN"2"28;
"A"
$PN"1"40;
%"RES"
"1","(300,1900)","0","mstr_discrete","I119";
;
CDS_SEC"1"
ROOM"DB1200Z"
SEC"1"
BOM_COST"SYS_CLOCK"
SEC_TYPE"0402"
CDS_LIB"mstr_discrete"
CDS_LOCATION"R4D20"
PART_NUMBER"G21796-182"
TOLERANCE"1%"
PACK_TYPE"0402"
MATERIAL"CHIP"
LOCATION"R4D20"
WATTAGE"1/16W"
VALUE"27.4";
"B"
$PN"2"36;
"A"
$PN"1"41;
%"RES"
"1","(-3325,4800)","0","mstr_discrete","I121";
;
CDS_SEC"1"
BOM_COST"SYS_CLOCK"
CDS_LIB"mstr_discrete"
SEC_TYPE"0402"
SEC"1"
ROOM"DB1200Z"
CDS_LOCATION"R7P9"
PACK_TYPE"0402"
MATERIAL"EMPTY"
TOLERANCE"1.0%"
LOCATION"R7P9"
PART_NUMBER"G21796-259"
VALUE"42.2"
WATTAGE"1/16W";
"B"
$PN"2"24;
"A"
$PN"1"51;
%"RES"
"1","(-3300,4425)","0","mstr_discrete","I123";
;
CDS_SEC"1"
BOM_COST"SYS_CLOCK"
SEC_TYPE"0402"
SEC"1"
ROOM"DB1200Z"
CDS_LIB"mstr_discrete"
CDS_LOCATION"R7P12"
PACK_TYPE"0402"
PART_NUMBER"G21796-259"
MATERIAL"EMPTY"
TOLERANCE"1.0%"
LOCATION"R7P12"
VALUE"42.2"
WATTAGE"1/16W";
"B"
$PN"2"23;
"A"
$PN"1"50;
%"RES"
"1","(-3325,4075)","0","mstr_discrete","I125";
;
CDS_SEC"1"
BOM_COST"SYS_CLOCK"
ROOM"DB1200Z"
CDS_LOCATION"R7P6"
SEC"1"
SEC_TYPE"0402"
CDS_LIB"mstr_discrete"
LOCATION"R7P6"
PART_NUMBER"G21796-259"
PACK_TYPE"0402"
MATERIAL"EMPTY"
TOLERANCE"1.0%"
VALUE"42.2"
WATTAGE"1/16W";
"B"
$PN"2"1;
"A"
$PN"1"49;
%"GND"
"1","(-2800,3975)","0","mstr_symbols","I126";
;
HDL_POWER"GND"
CDS_LIB"mstr_symbols"
SIZE"1B"
VOLTAGE"0.0V"
BODY_TYPE"PLUMBING";
"A\NAC"1;
%"RES"
"1","(-3325,3750)","0","mstr_discrete","I127";
;
CDS_LIB"mstr_discrete"
BOM_COST"SYS_CLOCK"
CDS_SEC"1"
$SEC"1"
ROOM"DB1200Z"
CDS_LOCATION"R7P7"
PART_NUMBER"G21796-259"
PACK_TYPE"0402"
MATERIAL"EMPTY"
TOLERANCE"1.0%"
LOCATION"R7P7"
VALUE"42.2"
WATTAGE"1/16W";
"B"
$PN"2"2;
"A"
$PN"1"57;
%"GND"
"1","(-2800,3650)","0","mstr_symbols","I128";
;
HDL_POWER"GND"
CDS_LIB"mstr_symbols"
SIZE"1B"
BODY_TYPE"PLUMBING"
VOLTAGE"0.0V";
"A\NAC"2;
%"RES"
"1","(-3325,3425)","0","mstr_discrete","I129";
;
CDS_SEC"1"
BOM_COST"SYS_CLOCK"
SEC_TYPE"0402"
SEC"1"
ROOM"DB1200Z"
CDS_LIB"mstr_discrete"
CDS_LOCATION"R7P3"
PART_NUMBER"G21796-259"
PACK_TYPE"0402"
TOLERANCE"1.0%"
MATERIAL"EMPTY"
LOCATION"R7P3"
VALUE"42.2"
WATTAGE"1/16W";
"B"
$PN"2"3;
"A"
$PN"1"56;
%"GND"
"1","(-2800,3325)","0","mstr_symbols","I130";
;
HDL_POWER"GND"
CDS_LIB"mstr_symbols"
SIZE"1B"
BODY_TYPE"PLUMBING"
VOLTAGE"0.0V";
"A\NAC"3;
%"RES"
"1","(-3325,3100)","0","mstr_discrete","I131";
;
CDS_SEC"1"
CDS_LIB"mstr_discrete"
BOM_COST"SYS_CLOCK"
SEC_TYPE"0402"
SEC"1"
ROOM"DB1200Z"
CDS_LOCATION"R7P4"
PART_NUMBER"G21796-259"
PACK_TYPE"0402"
LOCATION"R7P4"
MATERIAL"EMPTY"
TOLERANCE"1.0%"
VALUE"42.2"
WATTAGE"1/16W";
"B"
$PN"2"4;
"A"
$PN"1"55;
%"GND"
"1","(-2800,3000)","0","mstr_symbols","I132";
;
HDL_POWER"GND"
CDS_LIB"mstr_symbols"
SIZE"1B"
VOLTAGE"0.0V"
BODY_TYPE"PLUMBING";
"A\NAC"4;
%"RES"
"1","(-3325,2775)","0","mstr_discrete","I133";
;
CDS_SEC"1"
BOM_COST"SYS_CLOCK"
CDS_LIB"mstr_discrete"
SEC_TYPE"0402"
SEC"1"
ROOM"DB1200Z"
CDS_LOCATION"R7P1"
PART_NUMBER"G21796-259"
PACK_TYPE"0402"
MATERIAL"EMPTY"
TOLERANCE"1.0%"
LOCATION"R7P1"
VALUE"42.2"
WATTAGE"1/16W";
"B"
$PN"2"5;
"A"
$PN"1"54;
%"GND"
"1","(-2800,2675)","0","mstr_symbols","I134";
;
HDL_POWER"GND"
SIZE"1B"
CDS_LIB"mstr_symbols"
BODY_TYPE"PLUMBING"
VOLTAGE"0.0V";
"A\NAC"5;
%"RES"
"1","(-3325,2450)","0","mstr_discrete","I135";
;
CDS_SEC"1"
BOM_COST"SYS_CLOCK"
SEC_TYPE"0402"
ROOM"DB1200Z"
SEC"1"
CDS_LIB"mstr_discrete"
CDS_LOCATION"R7P2"
PART_NUMBER"G21796-259"
PACK_TYPE"0402"
TOLERANCE"1.0%"
MATERIAL"EMPTY"
LOCATION"R7P2"
VALUE"42.2"
WATTAGE"1/16W";
"B"
$PN"2"6;
"A"
$PN"1"53;
%"GND"
"1","(-2800,2350)","0","mstr_symbols","I136";
;
CDS_LIB"mstr_symbols"
HDL_POWER"GND"
SIZE"1B"
VOLTAGE"0.0V"
BODY_TYPE"PLUMBING";
"A\NAC"6;
%"RES"
"1","(-3325,2125)","0","mstr_discrete","I137";
;
CDS_SEC"1"
CDS_LIB"mstr_discrete"
BOM_COST"SYS_CLOCK"
SEC_TYPE"0402"
SEC"1"
ROOM"DB1200Z"
CDS_LOCATION"R6P7"
PART_NUMBER"G21796-259"
LOCATION"R6P7"
VALUE"42.2"
TOLERANCE"1.0%"
PACK_TYPE"0402"
MATERIAL"EMPTY"
WATTAGE"1/16W";
"B"
$PN"2"7;
"A"
$PN"1"52;
%"GND"
"1","(-2800,2025)","0","mstr_symbols","I138";
;
HDL_POWER"GND"
CDS_LIB"mstr_symbols"
SIZE"1B"
VOLTAGE"0.0V"
BODY_TYPE"PLUMBING";
"A\NAC"7;
%"RES"
"1","(-3325,1800)","0","mstr_discrete","I139";
;
CDS_SEC"1"
BOM_COST"SYS_CLOCK"
CDS_LIB"mstr_discrete"
SEC"1"
SEC_TYPE"0402"
ROOM"DB1200Z"
CDS_LOCATION"R6P8"
PART_NUMBER"G21796-259"
PACK_TYPE"0402"
MATERIAL"EMPTY"
TOLERANCE"1.0%"
LOCATION"R6P8"
VALUE"42.2"
WATTAGE"1/16W";
"B"
$PN"2"8;
"A"
$PN"1"60;
%"RES"
"1","(-3925,4525)","0","mstr_discrete","I14";
;
CDS_SEC"1"
SEC_TYPE"0402"
BOM_COST"SYS_CLOCK"
SEC"1"
ROOM"DB1200Z"
CDS_LIB"mstr_discrete"
CDS_LOCATION"R4D28"
LOCATION"R4D28"
PART_NUMBER"G21796-182"
PACK_TYPE"0402"
MATERIAL"CHIP"
TOLERANCE"1%"
WATTAGE"1/16W"
VALUE"27.4";
"B"
$PN"2"50;
"A"
$PN"1"62;
%"GND"
"1","(-2800,1700)","0","mstr_symbols","I140";
;
HDL_POWER"GND"
CDS_LIB"mstr_symbols"
SIZE"1B"
VOLTAGE"0.0V"
BODY_TYPE"PLUMBING";
"A\NAC"8;
%"RES"
"1","(-3325,1475)","0","mstr_discrete","I141";
;
CDS_SEC"1"
BOM_COST"SYS_CLOCK"
SEC_TYPE"0402"
SEC"1"
ROOM"DB1200Z"
CDS_LOCATION"R6P5"
CDS_LIB"mstr_discrete"
PART_NUMBER"G21796-259"
PACK_TYPE"0402"
LOCATION"R6P5"
MATERIAL"EMPTY"
TOLERANCE"1.0%"
VALUE"42.2"
WATTAGE"1/16W";
"B"
$PN"2"9;
"A"
$PN"1"59;
%"GND"
"1","(-2800,1375)","0","mstr_symbols","I142";
;
HDL_POWER"GND"
CDS_LIB"mstr_symbols"
SIZE"1B"
VOLTAGE"0.0V"
BODY_TYPE"PLUMBING";
"A\NAC"9;
%"RES"
"1","(-3325,1150)","0","mstr_discrete","I143";
;
CDS_SEC"1"
CDS_LIB"mstr_discrete"
BOM_COST"SYS_CLOCK"
SEC_TYPE"0402"
SEC"1"
ROOM"DB1200Z"
CDS_LOCATION"R6P6"
PART_NUMBER"G21796-259"
PACK_TYPE"0402"
TOLERANCE"1.0%"
LOCATION"R6P6"
VALUE"42.2"
MATERIAL"EMPTY"
WATTAGE"1/16W";
"B"
$PN"2"10;
"A"
$PN"1"58;
%"GND"
"1","(-2800,1050)","0","mstr_symbols","I144";
;
HDL_POWER"GND"
CDS_LIB"mstr_symbols"
SIZE"1B"
VOLTAGE"0.0V"
BODY_TYPE"PLUMBING";
"A\NAC"10;
%"RES"
"1","(1025,4725)","0","mstr_discrete","I145";
;
CDS_SEC"1"
CDS_LIB"mstr_discrete"
SEC_TYPE"0402"
BOM_COST"SYS_CLOCK"
SEC"1"
ROOM"DB1200Z"
CDS_LOCATION"R6P3"
PART_NUMBER"G21796-259"
TOLERANCE"1.0%"
PACK_TYPE"0402"
MATERIAL"EMPTY"
LOCATION"R6P3"
VALUE"42.2"
WATTAGE"1/16W";
"B"
$PN"2"11;
"A"
$PN"1"27;
%"GND"
"1","(1550,4625)","0","mstr_symbols","I146";
;
CDS_LIB"mstr_symbols"
HDL_POWER"GND"
SIZE"1B"
VOLTAGE"0.0V"
BODY_TYPE"PLUMBING";
"A\NAC"11;
%"RES"
"1","(1050,4400)","0","mstr_discrete","I147";
;
CDS_SEC"1"
CDS_LIB"mstr_discrete"
BOM_COST"SYS_CLOCK"
SEC_TYPE"0402"
SEC"1"
ROOM"DB1200Z"
CDS_LOCATION"R6P4"
PACK_TYPE"0402"
PART_NUMBER"G21796-259"
MATERIAL"EMPTY"
TOLERANCE"1.0%"
LOCATION"R6P4"
VALUE"42.2"
WATTAGE"1/16W";
"B"
$PN"2"12;
"A"
$PN"1"26;
%"GND"
"1","(1575,4300)","0","mstr_symbols","I148";
;
HDL_POWER"GND"
CDS_LIB"mstr_symbols"
SIZE"1B"
VOLTAGE"0.0V"
BODY_TYPE"PLUMBING";
"A\NAC"12;
%"RES"
"1","(1025,4075)","0","mstr_discrete","I149";
;
CDS_SEC"1"
BOM_COST"SYS_CLOCK"
SEC_TYPE"0402"
SEC"1"
ROOM"DB1200Z"
CDS_LOCATION"R6P1"
CDS_LIB"mstr_discrete"
LOCATION"R6P1"
PART_NUMBER"G21796-259"
PACK_TYPE"0402"
MATERIAL"EMPTY"
TOLERANCE"1.0%"
VALUE"42.2"
WATTAGE"1/16W";
"B"
$PN"2"13;
"A"
$PN"1"25;
%"GND"
"1","(1550,3975)","0","mstr_symbols","I150";
;
HDL_POWER"GND"
CDS_LIB"mstr_symbols"
SIZE"1B"
VOLTAGE"0.0V"
BODY_TYPE"PLUMBING";
"A\NAC"13;
%"RES"
"1","(1050,3750)","0","mstr_discrete","I151";
;
CDS_SEC"1"
CDS_LIB"mstr_discrete"
BOM_COST"SYS_CLOCK"
SEC_TYPE"0402"
SEC"1"
ROOM"DB1200Z"
CDS_LOCATION"R6P2"
PACK_TYPE"0402"
PART_NUMBER"G21796-259"
MATERIAL"EMPTY"
TOLERANCE"1.0%"
LOCATION"R6P2"
VALUE"42.2"
WATTAGE"1/16W";
"B"
$PN"2"14;
"A"
$PN"1"33;
%"GND"
"1","(1575,3650)","0","mstr_symbols","I152";
;
HDL_POWER"GND"
CDS_LIB"mstr_symbols"
SIZE"1B"
VOLTAGE"0.0V"
BODY_TYPE"PLUMBING";
"A\NAC"14;
%"RES"
"1","(1050,3425)","0","mstr_discrete","I153";
;
CDS_SEC"1"
CDS_LIB"mstr_discrete"
BOM_COST"SYS_CLOCK"
SEC_TYPE"0402"
SEC"1"
ROOM"DB1200Z"
CDS_LOCATION"R6P11"
PACK_TYPE"0402"
PART_NUMBER"G21796-259"
TOLERANCE"1.0%"
MATERIAL"EMPTY"
LOCATION"R6P11"
VALUE"42.2"
WATTAGE"1/16W";
"B"
$PN"2"15;
"A"
$PN"1"32;
%"GND"
"1","(1575,3325)","0","mstr_symbols","I154";
;
HDL_POWER"GND"
CDS_LIB"mstr_symbols"
SIZE"1B"
VOLTAGE"0.0V"
BODY_TYPE"PLUMBING";
"A\NAC"15;
%"RES"
"1","(1075,3100)","0","mstr_discrete","I155";
;
CDS_SEC"1"
BOM_COST"SYS_CLOCK"
SEC_TYPE"0402"
SEC"1"
ROOM"DB1200Z"
CDS_LIB"mstr_discrete"
CDS_LOCATION"R6P9"
PART_NUMBER"G21796-259"
LOCATION"R6P9"
PACK_TYPE"0402"
MATERIAL"EMPTY"
TOLERANCE"1.0%"
VALUE"42.2"
WATTAGE"1/16W";
"B"
$PN"2"16;
"A"
$PN"1"31;
%"GND"
"1","(1600,3000)","0","mstr_symbols","I156";
;
HDL_POWER"GND"
VOLTAGE"0.0V"
SIZE"1B"
CDS_LIB"mstr_symbols"
BODY_TYPE"PLUMBING";
"A\NAC"16;
%"RES"
"1","(1050,2775)","0","mstr_discrete","I157";
;
CDS_SEC"1"
CDS_LIB"mstr_discrete"
BOM_COST"SYS_CLOCK"
ROOM"DB1200Z"
CDS_LOCATION"R6P13"
SEC"1"
SEC_TYPE"0402"
PACK_TYPE"0402"
PART_NUMBER"G21796-259"
MATERIAL"EMPTY"
TOLERANCE"1.0%"
LOCATION"R6P13"
VALUE"42.2"
WATTAGE"1/16W";
"B"
$PN"2"17;
"A"
$PN"1"30;
%"GND"
"1","(1575,2675)","0","mstr_symbols","I158";
;
HDL_POWER"GND"
CDS_LIB"mstr_symbols"
SIZE"1B"
VOLTAGE"0.0V"
BODY_TYPE"PLUMBING";
"A\NAC"17;
%"RES"
"1","(1050,2450)","0","mstr_discrete","I159";
;
CDS_SEC"1"
CDS_LIB"mstr_discrete"
BOM_COST"SYS_CLOCK"
SEC_TYPE"0402"
ROOM"DB1200Z"
SEC"1"
CDS_LOCATION"R6P12"
PACK_TYPE"0402"
PART_NUMBER"G21796-259"
TOLERANCE"1.0%"
MATERIAL"EMPTY"
LOCATION"R6P12"
VALUE"42.2"
WATTAGE"1/16W";
"B"
$PN"2"18;
"A"
$PN"1"29;
%"GND"
"1","(1575,2350)","0","mstr_symbols","I160";
;
HDL_POWER"GND"
CDS_LIB"mstr_symbols"
SIZE"1B"
VOLTAGE"0.0V"
BODY_TYPE"PLUMBING";
"A\NAC"18;
%"RES"
"1","(1050,2125)","0","mstr_discrete","I161";
;
CDS_SEC"1"
CDS_LIB"mstr_discrete"
BOM_COST"SYS_CLOCK"
SEC_TYPE"0402"
SEC"1"
ROOM"DB1200Z"
CDS_LOCATION"R4D24"
PART_NUMBER"G21796-259"
LOCATION"R4D24"
VALUE"42.2"
TOLERANCE"1.0%"
PACK_TYPE"0402"
MATERIAL"EMPTY"
WATTAGE"1/16W";
"B"
$PN"2"19;
"A"
$PN"1"28;
%"GND"
"1","(1575,2025)","0","mstr_symbols","I162";
;
HDL_POWER"GND"
CDS_LIB"mstr_symbols"
SIZE"1B"
VOLTAGE"0.0V"
BODY_TYPE"PLUMBING";
"A\NAC"19;
%"RES"
"1","(1050,1800)","0","mstr_discrete","I163";
;
CDS_SEC"1"
BOM_COST"SYS_CLOCK"
CDS_LIB"mstr_discrete"
SEC"1"
SEC_TYPE"0402"
ROOM"DB1200Z"
CDS_LOCATION"R4D18"
PACK_TYPE"0402"
PART_NUMBER"G21796-259"
MATERIAL"EMPTY"
TOLERANCE"1.0%"
LOCATION"R4D18"
VALUE"42.2"
WATTAGE"1/16W";
"B"
$PN"2"20;
"A"
$PN"1"36;
%"GND"
"1","(1575,1700)","0","mstr_symbols","I164";
;
HDL_POWER"GND"
SIZE"1B"
CDS_LIB"mstr_symbols"
VOLTAGE"0.0V"
BODY_TYPE"PLUMBING";
"A\NAC"20;
%"RES"
"1","(1050,1475)","0","mstr_discrete","I165";
;
CDS_SEC"1"
CDS_LIB"mstr_discrete"
BOM_COST"SYS_CLOCK"
SEC_TYPE"0402"
SEC"1"
ROOM"DB1200Z"
CDS_LOCATION"R6P17"
PACK_TYPE"0402"
PART_NUMBER"G21796-259"
MATERIAL"EMPTY"
TOLERANCE"1.0%"
LOCATION"R6P17"
VALUE"42.2"
WATTAGE"1/16W";
"B"
$PN"2"21;
"A"
$PN"1"35;
%"GND"
"1","(1575,1375)","0","mstr_symbols","I166";
;
HDL_POWER"GND"
CDS_LIB"mstr_symbols"
SIZE"1B"
VOLTAGE"0.0V"
BODY_TYPE"PLUMBING";
"A\NAC"21;
%"RES"
"1","(1050,1150)","0","mstr_discrete","I167";
;
CDS_SEC"1"
CDS_LIB"mstr_discrete"
BOM_COST"SYS_CLOCK"
SEC_TYPE"0402"
SEC"1"
ROOM"DB1200Z"
CDS_LOCATION"R6P15"
PART_NUMBER"G21796-259"
TOLERANCE"1.0%"
MATERIAL"EMPTY"
PACK_TYPE"0402"
LOCATION"R6P15"
VALUE"42.2"
WATTAGE"1/16W";
"B"
$PN"2"22;
"A"
$PN"1"34;
%"GND"
"1","(1575,1050)","0","mstr_symbols","I168";
;
CDS_LIB"mstr_symbols"
HDL_POWER"GND"
SIZE"1B"
VOLTAGE"0.0V"
BODY_TYPE"PLUMBING";
"A\NAC"22;
%"GND"
"1","(-2775,4325)","0","mstr_symbols","I169";
;
HDL_POWER"GND"
CDS_LIB"mstr_symbols"
SIZE"1B"
BODY_TYPE"PLUMBING"
VOLTAGE"0.0V";
"A\NAC"23;
%"GND"
"1","(-2800,4700)","0","mstr_symbols","I170";
;
HDL_POWER"GND"
CDS_LIB"mstr_symbols"
SIZE"1B"
VOLTAGE"0.0V"
BODY_TYPE"PLUMBING";
"A\NAC"24;
%"RES"
"1","(-3925,4175)","0","mstr_discrete","I19";
;
CDS_SEC"1"
SEC"1"
SEC_TYPE"0402"
BOM_COST"SYS_CLOCK"
ROOM"DB1200Z"
CDS_LIB"mstr_discrete"
CDS_LOCATION"R4D19"
PART_NUMBER"G21796-182"
LOCATION"R4D19"
MATERIAL"CHIP"
TOLERANCE"1%"
PACK_TYPE"0402"
WATTAGE"1/16W"
VALUE"27.4";
"B"
$PN"2"49;
"A"
$PN"1"63;
%"RES"
"1","(-3925,3850)","0","mstr_discrete","I24";
;
CDS_SEC"1"
BOM_COST"SYS_CLOCK"
CDS_LIB"mstr_discrete"
SEC_TYPE"0402"
SEC"1"
CDS_LOCATION"R4D21"
ROOM"DB1200Z"
PART_NUMBER"G21796-182"
LOCATION"R4D21"
PACK_TYPE"0402"
MATERIAL"CHIP"
TOLERANCE"1%"
WATTAGE"1/16W"
VALUE"27.4";
"B"
$PN"2"57;
"A"
$PN"1"64;
%"RES"
"1","(-3925,3525)","0","mstr_discrete","I29";
;
CDS_SEC"1"
BOM_COST"SYS_CLOCK"
SEC_TYPE"0402"
SEC"1"
ROOM"DB1200Z"
CDS_LOCATION"R4D13"
CDS_LIB"mstr_discrete"
PART_NUMBER"G21796-182"
LOCATION"R4D13"
PACK_TYPE"0402"
MATERIAL"CHIP"
TOLERANCE"1%"
WATTAGE"1/16W"
VALUE"27.4";
"B"
$PN"2"56;
"A"
$PN"1"65;
%"RES"
"1","(-3925,3200)","0","mstr_discrete","I34";
;
CDS_SEC"1"
ROOM"DB1200Z"
SEC"1"
BOM_COST"SYS_CLOCK"
SEC_TYPE"0402"
CDS_LIB"mstr_discrete"
CDS_LOCATION"R4D16"
PART_NUMBER"G21796-182"
LOCATION"R4D16"
PACK_TYPE"0402"
MATERIAL"CHIP"
TOLERANCE"1%"
WATTAGE"1/16W"
VALUE"27.4";
"B"
$PN"2"55;
"A"
$PN"1"66;
%"RES"
"1","(-3925,2875)","0","mstr_discrete","I39";
;
CDS_SEC"1"
SEC"1"
BOM_COST"SYS_CLOCK"
SEC_TYPE"0402"
CDS_LIB"mstr_discrete"
ROOM"DB1200Z"
CDS_LOCATION"R4D9"
PART_NUMBER"G21796-182"
PACK_TYPE"0402"
MATERIAL"CHIP"
LOCATION"R4D9"
TOLERANCE"1%"
WATTAGE"1/16W"
VALUE"27.4";
"B"
$PN"2"54;
"A"
$PN"1"67;
%"RES"
"1","(-3925,2550)","0","mstr_discrete","I44";
;
CDS_SEC"1"
BOM_COST"SYS_CLOCK"
SEC_TYPE"0402"
CDS_LOCATION"R4D11"
ROOM"DB1200Z"
SEC"1"
CDS_LIB"mstr_discrete"
PART_NUMBER"G21796-182"
LOCATION"R4D11"
PACK_TYPE"0402"
MATERIAL"CHIP"
TOLERANCE"1%"
WATTAGE"1/16W"
VALUE"27.4";
"B"
$PN"2"53;
"A"
$PN"1"68;
%"RES"
"1","(-3925,2225)","0","mstr_discrete","I49";
;
BOM_COST"SYS_CLOCK"
CDS_SEC"1"
$SEC"1"
ROOM"DB1200Z"
CDS_LIB"mstr_discrete"
CDS_LOCATION"R4D2"
PART_NUMBER"G21796-182"
PACK_TYPE"0402"
MATERIAL"CHIP"
TOLERANCE"1%"
LOCATION"R4D2"
WATTAGE"1/16W"
VALUE"27.4";
"B"
$PN"2"52;
"A"
$PN"1"69;
%"RES"
"1","(-3925,1900)","0","mstr_discrete","I54";
;
CDS_SEC"1"
SEC"1"
ROOM"DB1200Z"
BOM_COST"SYS_CLOCK"
SEC_TYPE"0402"
CDS_LIB"mstr_discrete"
CDS_LOCATION"R4D1"
PART_NUMBER"G21796-182"
PACK_TYPE"0402"
MATERIAL"CHIP"
TOLERANCE"1%"
WATTAGE"1/16W"
LOCATION"R4D1"
VALUE"27.4";
"B"
$PN"2"60;
"A"
$PN"1"70;
%"RES"
"1","(-3925,1575)","0","mstr_discrete","I59";
;
CDS_SEC"1"
BOM_COST"SYS_CLOCK"
SEC_TYPE"0402"
SEC"1"
CDS_LIB"mstr_discrete"
ROOM"DB1200Z"
CDS_LOCATION"R4D4"
PART_NUMBER"G21796-182"
LOCATION"R4D4"
MATERIAL"CHIP"
PACK_TYPE"0402"
TOLERANCE"1%"
WATTAGE"1/16W"
VALUE"27.4";
"B"
$PN"2"59;
"A"
$PN"1"71;
%"RES"
"1","(-3925,1250)","0","mstr_discrete","I64";
;
CDS_SEC"1"
BOM_COST"SYS_CLOCK"
SEC_TYPE"0402"
SEC"1"
CDS_LOCATION"R4D3"
ROOM"DB1200Z"
CDS_LIB"mstr_discrete"
PART_NUMBER"G21796-182"
MATERIAL"CHIP"
PACK_TYPE"0402"
LOCATION"R4D3"
TOLERANCE"1%"
WATTAGE"1/16W"
VALUE"27.4";
"B"
$PN"2"58;
"A"
$PN"1"72;
%"RES"
"1","(300,1575)","0","mstr_discrete","I69";
;
CDS_SEC"1"
CDS_LIB"mstr_discrete"
SEC_TYPE"0402"
BOM_COST"SYS_CLOCK"
SEC"1"
CDS_LOCATION"R4D29"
ROOM"DB1200Z"
PART_NUMBER"G21796-182"
LOCATION"R4D29"
VALUE"27.4"
MATERIAL"CHIP"
TOLERANCE"1%"
PACK_TYPE"0402"
WATTAGE"1/16W";
"B"
$PN"2"35;
"A"
$PN"1"43;
%"RES"
"1","(300,4825)","0","mstr_discrete","I74";
;
CDS_SEC"1"
CDS_LIB"mstr_discrete"
SEC_TYPE"0402"
BOM_COST"SYS_CLOCK"
SEC"1"
CDS_LOCATION"R4D6"
ROOM"DB1200Z"
PART_NUMBER"G21796-182"
TOLERANCE"1%"
PACK_TYPE"0402"
MATERIAL"CHIP"
LOCATION"R4D6"
WATTAGE"1/16W"
VALUE"27.4";
"B"
$PN"2"27;
"A"
$PN"1"44;
%"RES"
"1","(300,4500)","0","mstr_discrete","I79";
;
CDS_SEC"1"
ROOM"DB1200Z"
SEC"1"
BOM_COST"SYS_CLOCK"
SEC_TYPE"0402"
CDS_LIB"mstr_discrete"
CDS_LOCATION"R4D5"
PART_NUMBER"G21796-182"
TOLERANCE"1%"
PACK_TYPE"0402"
MATERIAL"CHIP"
LOCATION"R4D5"
WATTAGE"1/16W"
VALUE"27.4";
"B"
$PN"2"26;
"A"
$PN"1"45;
%"RES"
"1","(300,4175)","0","mstr_discrete","I84";
;
CDS_SEC"1"
CDS_LIB"mstr_discrete"
SEC_TYPE"0402"
BOM_COST"SYS_CLOCK"
SEC"1"
CDS_LOCATION"R4D8"
ROOM"DB1200Z"
PART_NUMBER"G21796-182"
MATERIAL"CHIP"
LOCATION"R4D8"
VALUE"27.4"
TOLERANCE"1%"
PACK_TYPE"0402"
WATTAGE"1/16W";
"B"
$PN"2"25;
"A"
$PN"1"46;
%"RES"
"1","(300,3850)","0","mstr_discrete","I89";
;
CDS_SEC"1"
BOM_COST"SYS_CLOCK"
CDS_LIB"mstr_discrete"
SEC_TYPE"0402"
SEC"1"
CDS_LOCATION"R4D7"
ROOM"DB1200Z"
PART_NUMBER"G21796-182"
TOLERANCE"1%"
PACK_TYPE"0402"
MATERIAL"CHIP"
LOCATION"R4D7"
WATTAGE"1/16W"
VALUE"27.4";
"B"
$PN"2"33;
"A"
$PN"1"47;
%"RES"
"1","(-3925,4900)","0","mstr_discrete","I9";
;
CDS_SEC"1"
BOM_COST"SYS_CLOCK"
SEC_TYPE"0402"
SEC"1"
CDS_LIB"mstr_discrete"
CDS_LOCATION"R4D23"
ROOM"DB1200Z"
PACK_TYPE"0402"
MATERIAL"CHIP"
PART_NUMBER"G21796-182"
LOCATION"R4D23"
TOLERANCE"1%"
WATTAGE"1/16W"
VALUE"27.4";
"B"
$PN"2"51;
"A"
$PN"1"61;
%"RES"
"1","(300,3525)","0","mstr_discrete","I94";
;
CDS_SEC"1"
ROOM"DB1200Z"
SEC"1"
SEC_TYPE"0402"
BOM_COST"SYS_CLOCK"
CDS_LOCATION"R4D12"
CDS_LIB"mstr_discrete"
PART_NUMBER"G21796-182"
LOCATION"R4D12"
TOLERANCE"1%"
PACK_TYPE"0402"
MATERIAL"CHIP"
WATTAGE"1/16W"
VALUE"27.4";
"B"
$PN"2"32;
"A"
$PN"1"48;
%"RES"
"1","(300,3200)","0","mstr_discrete","I99";
;
CDS_SEC"1"
CDS_LIB"mstr_discrete"
SEC"1"
SEC_TYPE"0402"
BOM_COST"SYS_CLOCK"
ROOM"DB1200Z"
CDS_LOCATION"R4D10"
PART_NUMBER"G21796-182"
TOLERANCE"1%"
PACK_TYPE"0402"
MATERIAL"CHIP"
LOCATION"R4D10"
WATTAGE"1/16W"
VALUE"27.4";
"B"
$PN"2"31;
"A"
$PN"1"37;
END.
